FILE_TYPE = MACRO_DRAWING;
SET COLOR_WIRE YELLOW;
SET COLOR_PROP ORANGE;
SET COLOR_DOT WHITE;
SET COLOR_ARC YELLOW;
SET COLOR_BODY GREEN;
SET COLOR_NOTE PURPLE;
SET PROP_DISPLAY VALUE;
SET PAGE_NUMBER P208;
FORCEADD QUANTA_TITLE_BLOCK_C..1
(5625 -1650);
FORCEPROP 1 LAST CUSTOM_TXT_CDS <NAME_2>
J 0
(2450 -1600);
FORCEPROP 1 LAST CUSTOM_TXT_CDS <NAME_1>
J 0
(2450 -1475);
FORCEPROP 1 LAST CUSTOM_TXT_CDS <Q_NUMBER>
J 0
(4222 -1547);
DISPLAY 1.212766 (4222 -1547);
FORCEPROP 1 LAST CUSTOM_TXT_CDS <Q_PROJ>
J 0
(3243 -1548);
DISPLAY 1.212766 (3243 -1548);
FORCEPROP 1 LAST CUSTOM_TXT_CDS <Q_REV>
J 0
(5441 -1547);
DISPLAY 1.212766 (5441 -1547);
FORCEPROP 1 LAST CUSTOM_TXT_CDS <CON_LAST_MODIFIED>
J 0
(3740 -1635);
DISPLAY 0.978723 (3740 -1635);
FORCEPROP 1 LAST CUSTOM_TXT_CDS <CON_PAGE_NUM> OF <CON_TOTAL_PAGES>
J 0
(5179 -1632);
DISPLAY 0.978723 (5179 -1632);
FORCEPROP 1 LAST Q_TITLE eFUSE - OCP
J 0
(-3675 -1600);
DISPLAY 2.446809 (-3675 -1600);
PAINT GREEN (-3675 -1600);
FORCEPROP 1 LAST Q_DEPT BU9
J 1
(1862 -1601);
DISPLAY 1.957447 (1862 -1601);
PAINT GREEN (1862 -1601);
FORCEPROP 2 LAST CDS_LIB pure_quanta
J 0
(5625 -1650);
DISPLAY INVISIBLE (5625 -1650);
FORCEPROP 1 LAST CDS_LMAN_SYM_OUTLINE -9475,6775,100,-125
J 0
(5625 -1650);
DISPLAY 0.468085 (5625 -1650);
PAINT GREEN (5625 -1650);
DISPLAY INVISIBLE (5625 -1650);
FORCEPROP 2 LAST PAGE_BORDER TRUE
J 0
(-2265 3600);
DISPLAY 0.638298 (-2265 3600);
PAINT PINK (-2265 3600);
DISPLAY INVISIBLE (-2265 3600);
FORCEPROP 1 LAST COMMENT_BODY TRUE
J 0
(5637 -1663);
DISPLAY 0.978723 (5637 -1663);
PAINT GREEN (5637 -1663);
DISPLAY INVISIBLE (5637 -1663);
FORCEPROP 2 LAST CDS_XR_PAGE_TITLE CR-209 : @T6G_MB_LIB.T6G(SCH_1):PAGE209
J 0
(-2265 3600);
DISPLAY 0.638298 (-2265 3600);
PAINT PINK (-2265 3600);
DISPLAY INVISIBLE (-2265 3600);
FORCEPROP 2 LAST CUSTOM_TXT_CDS <XR_PAGE_TITLE>
J 0
(-2265 3600);
DISPLAY 0.638298 (-2265 3600);
PAINT PINK (-2265 3600);
DISPLAY INVISIBLE (-2265 3600);
FORCEPROP 0 LAST CDS_CON_LAST_MODIFIED Wed Mar 09 21:46:51 2022
J 0
(3740 -1635);
DISPLAY INVISIBLE (3740 -1635);
QUIT
